G04 ================== begin FILE IDENTIFICATION RECORD ==================*
G04 Layout Name:  13130-1b.brd*
G04 Film Name:    P_OUTLINE*
G04 File Format:  Gerber RS274X*
G04 File Origin:  Cadence Allegro 16.5-S037*
G04 Origin Date:  Thu Nov 13 17:26:01 2014*
G04 *
G04 Layer:  BOARD GEOMETRY/PANEL_OUTLINE*
G04 *
G04 Offset:    (0.00 0.00)*
G04 Mirror:    No*
G04 Mode:      Positive*
G04 Rotation:  0*
G04 FullContactRelief:  No*
G04 UndefLineWidth:     6.00*
G04 ================== end FILE IDENTIFICATION RECORD ====================*
%FSLAX35Y35*MOIN*%
%IR0*IPPOS*OFA0.00000B0.00000*MIA0B0*SFA1.00000B1.00000*%
%ADD10C,.006*%
G75*
%LPD*%
G75*
G54D10*
G01X-31497Y-1D02*
X26377D01*
G01X-35434Y3936D02*
G03X-31497Y-1I3937J0D01*
G01X-35434Y585039D02*
Y3936D01*
G01X-7874Y588976D02*
X-31497D01*
G01D02*
G03X-35434Y585039I0J-3937D01*
G01X-12698Y15747D02*
G03I-6988J0D01*
G01Y573227D02*
G03I-6988J0D01*
G01X826773Y286614D02*
G03X822836Y290551I-3937J0D01*
G01X3938D01*
G03X1Y286614I0J-3937D01*
G01Y61811D01*
G03X3938Y57874I3937J0D01*
G01X53938D01*
G02X57875Y53937I0J-3937D01*
G01Y12598D01*
X59844Y10629D01*
X336222D01*
X338190Y12598D01*
Y39960D01*
G02X345671I3740J0D01*
G01Y12598D01*
X347639Y10629D01*
X387797D01*
X389765Y12598D01*
Y42126D01*
G02X393702Y46063I3937J0D01*
G01X409450D01*
G02X413387Y42126I0J-3937D01*
G01Y3937D01*
G03X417324Y0I3937J0D01*
G01X822836D01*
G03X826773Y3937I0J3937D01*
G01Y286614D01*
G01X22440Y49999D02*
X-3937D01*
G01X-7874Y53936D02*
Y72440D01*
G01Y53936D02*
G03X-3937Y49999I3937J0D01*
G01X0Y72440D02*
G03X-7874I-3937J0D01*
G01Y103149D02*
G03X0I3937J0D01*
G01X-7874D02*
Y210235D01*
G01X0D02*
G03X-7874I-3937J0D01*
G01Y240944D02*
Y348031D01*
G01Y240944D02*
G03X0I3937J0D01*
G01X-3Y302361D02*
G03X3934Y298424I3937J0D01*
G01X822832D01*
G03X826769Y302361I0J3937D01*
G01Y527164D01*
G03X822832Y531101I-3937J0D01*
G01X772832D01*
G02X768895Y535038I0J3937D01*
G01Y576377D01*
X766926Y578346D01*
X490548D01*
X488580Y576377D01*
Y549015D01*
G02X481099I-3740J0D01*
G01Y576377D01*
X479131Y578346D01*
X438973D01*
X437005Y576377D01*
Y546849D01*
G02X433068Y542912I-3937J0D01*
G01X417320D01*
G02X413383Y546849I0J3937D01*
G01Y585038D01*
G03X409446Y588975I-3937J0D01*
G01X3934D01*
G03X-3Y585038I0J-3937D01*
G01Y302361D01*
G01X0Y348031D02*
G03X-7874I-3937J0D01*
G01Y378739D02*
Y485826D01*
G01Y378739D02*
G03X0I3937J0D01*
G01Y485826D02*
G03X-7874I-3937J0D01*
G01Y516535D02*
Y588976D01*
G01Y516535D02*
G03X0I3937J-1D01*
G01X26377Y-1D02*
Y46062D01*
G01D02*
G03X22440Y49999I-3937J0D01*
G01X102756Y290550D02*
G03Y298424I0J3937D01*
G01X133465D02*
G03Y290550I0J-3937D01*
G01X299606Y290551D02*
G03Y298425I0J3937D01*
G01X330314D02*
G03Y290551I0J-3937D01*
G01X496457Y290550D02*
G03Y298424I0J3937D01*
G01X527166D02*
G03Y290550I0J-3937D01*
G01X693308D02*
G03Y298424I0J3937D01*
G01X724016D02*
G03Y290550I0J-3937D01*
G01X800393Y588976D02*
Y542913D01*
G01D02*
G03X804330Y538976I3937J0D01*
G01X858267Y588976D02*
X800393D01*
G01X804330Y538976D02*
X830708D01*
G01X834645Y72440D02*
G03X826771I-3937J0D01*
G01Y103149D02*
G03X834645I3937J0D01*
G01Y210235D02*
G03X826771I-3937J0D01*
G01Y240944D02*
G03X834645I3937J0D01*
G01Y348031D02*
G03X826771I-3937J0D01*
G01Y378739D02*
G03X834645I3937J0D01*
G01Y485826D02*
G03X826771I-3937J0D01*
G01Y516535D02*
G03X834645I3937J-1D01*
G01Y535039D02*
G03X830708Y538976I-3937J0D01*
G01X834645Y72440D02*
Y-1D01*
G01D02*
X858267D01*
G01X853444Y15747D02*
G03I-6988J0D01*
G01X834645Y210235D02*
Y103149D01*
G01Y348031D02*
Y240944D01*
G01Y485826D02*
Y378739D01*
G01Y535039D02*
Y516535D01*
G01X853444Y573227D02*
G03I-6988J0D01*
G01X862204Y3936D02*
Y585039D01*
G01X858267Y-1D02*
G03X862204Y3936I0J3937D01*
G01Y585039D02*
G03X858267Y588976I-3937J0D01*
M02*
